# S9S_MB_2U (Grand Teton) — schematic netlist excerpt (pin names and nets, part order shuffled) for the footprints in the layout excerpt that follows; sources: Cadence DE-HDL packaged netlist, KiCad conversion of 03242023_DA0F0TMBIJ0_F0T_Motherboard_J_brd_V01_OCP.brd

R4301  Q_RES  100 1% CHIP  pkg 0402LF  page 125 : A = PWRGD_DRAMPWRGD_CPU1_EF_LVC1_R2 ; B = PWRGD_DRAMPWRGD_CPU1_EF_LVC1_R
R5  Q_RES  100 1% CHIP  pkg 0402LF  page 13 : A = JTAG_DBP_CPU_GTL_TCK ; B = JTAG_DBP_CPU0_GTL_R_TCK

(kicad_pcb
	(version 20260206)
	(generator "pcbnew")
	(generator_version "10.0")
	(general
		(thickness 1.6)
		(legacy_teardrops no)
	)
	(paper "A4")
	(title_block
		(title "03242023_DA0F0TMBIJ0_F0T_Motherboard_J_brd_V01_OCP.brd")
		(comment 1 "Grand Teton / footprints 5839-5840 of 6105")
	)
	(layers
		(0 "F.Cu" signal "TOP")
		(4 "In1.Cu" signal "GND")
		(6 "In2.Cu" signal "IN1")
		(8 "In3.Cu" signal "GND1")
		(10 "In4.Cu" signal "IN2")
		(12 "In5.Cu" signal "GND2")
		(14 "In6.Cu" signal "IN3")
		(16 "In7.Cu" signal "GND3")
		(18 "In8.Cu" signal "VCC")
		(20 "In9.Cu" signal "VCC1")
		(22 "In10.Cu" signal "GND4")
		(24 "In11.Cu" signal "IN4")
		(26 "In12.Cu" signal "GND5")
		(28 "In13.Cu" signal "IN5")
		(30 "In14.Cu" signal "GND6")
		(32 "In15.Cu" signal "IN6")
		(34 "In16.Cu" signal "GND7")
		(2 "B.Cu" signal "BOTTOM")
		(9 "F.Adhes" user "F.Adhesive")
		(11 "B.Adhes" user "B.Adhesive")
		(13 "F.Paste" user "Package Geometry/Pastemask Top")
		(15 "B.Paste" user "Package Geometry/Pastemask Bottom")
		(5 "F.SilkS" user "Ref Des/Silkscreen Top")
		(7 "B.SilkS" user "Ref Des/Silkscreen Bottom")
		(1 "F.Mask" user "Board Geometry/Soldermask Top")
		(3 "B.Mask" user "Board Geometry/Soldermask Bottom")
		(17 "Dwgs.User" user "User.Drawings")
		(19 "Cmts.User" user "User.Comments")
		(21 "Eco1.User" user "User.Eco1")
		(23 "Eco2.User" user "User.Eco2")
		(25 "Edge.Cuts" user "Board Geometry/Outline")
		(27 "Margin" user)
		(31 "F.CrtYd" user "Package Geometry/Place Bound Top")
		(29 "B.CrtYd" user "Package Geometry/Place Bound Bottom")
		(35 "F.Fab" user "Ref Des/Assembly Top")
		(33 "B.Fab" user "Ref Des/Assembly Bottom")
	)
	(footprint ""
		(layer "B.Cu")
		(at 325.322438 -188.45911 -90)
		(property "Reference" "R5"
			(at 0 0 90)
			(layer "B.SilkS")
			(hide yes)
			(effects
				(font
					(size 1.27 1.27)
				)
				(justify mirror)
			)
		)
		(property "Value" ""
			(at 0 0 90)
			(layer "B.Fab")
			(effects
				(font
					(size 1.27 1.27)
				)
				(justify mirror)
			)
		)
		(duplicate_pad_numbers_are_jumpers no)
		(fp_line
			(start -0.7874 0.4064)
			(end 0.7874 0.4064)
			(stroke
				(width 0.1524)
				(type default)
			)
			(layer "B.SilkS")
		)
		(fp_line
			(start 0.7874 0.4064)
			(end 0.7874 -0.4064)
			(stroke
				(width 0.1524)
				(type default)
			)
			(layer "B.SilkS")
		)
		(fp_line
			(start -0.7874 -0.4064)
			(end -0.7874 0.4064)
			(stroke
				(width 0.1524)
				(type default)
			)
			(layer "B.SilkS")
		)
		(fp_line
			(start 0.7874 -0.4064)
			(end -0.7874 -0.4064)
			(stroke
				(width 0.1524)
				(type default)
			)
			(layer "B.SilkS")
		)
		(fp_line
			(start -0.67945 0.3048)
			(end -0.120396 0.3048)
			(stroke
				(width 0.1)
				(type default)
			)
			(layer "B.Fab")
		)
		(fp_line
			(start -0.120396 0.3048)
			(end -0.120396 0.2794)
			(stroke
				(width 0.1)
				(type default)
			)
			(layer "B.Fab")
		)
		(fp_line
			(start 0.12065 0.3048)
			(end 0.67945 0.3048)
			(stroke
				(width 0.1)
				(type default)
			)
			(layer "B.Fab")
		)
		(fp_line
			(start 0.67945 0.3048)
			(end 0.67945 -0.305054)
			(stroke
				(width 0.1)
				(type default)
			)
			(layer "B.Fab")
		)
		(fp_line
			(start -0.120396 0.2794)
			(end 0.12065 0.2794)
			(stroke
				(width 0.1)
				(type default)
			)
			(layer "B.Fab")
		)
		(fp_line
			(start 0.12065 0.2794)
			(end 0.12065 0.3048)
			(stroke
				(width 0.1)
				(type default)
			)
			(layer "B.Fab")
		)
		(fp_line
			(start -0.12065 -0.2794)
			(end -0.12065 -0.3048)
			(stroke
				(width 0.1)
				(type default)
			)
			(layer "B.Fab")
		)
		(fp_line
			(start 0.12065 -0.2794)
			(end -0.12065 -0.2794)
			(stroke
				(width 0.1)
				(type default)
			)
			(layer "B.Fab")
		)
		(fp_line
			(start -0.67945 -0.3048)
			(end -0.67945 0.3048)
			(stroke
				(width 0.1)
				(type default)
			)
			(layer "B.Fab")
		)
		(fp_line
			(start -0.12065 -0.3048)
			(end -0.67945 -0.3048)
			(stroke
				(width 0.1)
				(type default)
			)
			(layer "B.Fab")
		)
		(fp_line
			(start 0.12065 -0.305054)
			(end 0.12065 -0.2794)
			(stroke
				(width 0.1)
				(type default)
			)
			(layer "B.Fab")
		)
		(fp_line
			(start 0.67945 -0.305054)
			(end 0.12065 -0.305054)
			(stroke
				(width 0.1)
				(type default)
			)
			(layer "B.Fab")
		)
		(pad "1" smd circle
			(at 0.40005 0 90)
			(size 0 0)
			(layers "B.Cu" "B.Mask" "B.Paste")
			(net "JTAG_DBP_CPU_GTL_TCK")
		)
		(pad "2" smd circle
			(at -0.40005 0 90)
			(size 0 0)
			(layers "B.Cu" "B.Mask" "B.Paste")
			(net "JTAG_DBP_CPU0_GTL_R_TCK")
		)
	)
	(footprint ""
		(layer "B.Cu")
		(at 168.742868 -197.131178 -90)
		(property "Reference" "R4301"
			(at 0 0 90)
			(layer "B.SilkS")
			(hide yes)
			(effects
				(font
					(size 1.27 1.27)
				)
				(justify mirror)
			)
		)
		(property "Value" ""
			(at 0 0 90)
			(layer "B.Fab")
			(effects
				(font
					(size 1.27 1.27)
				)
				(justify mirror)
			)
		)
		(duplicate_pad_numbers_are_jumpers no)
		(fp_line
			(start -0.7874 0.4064)
			(end 0.7874 0.4064)
			(stroke
				(width 0.1524)
				(type default)
			)
			(layer "B.SilkS")
		)
		(fp_line
			(start 0.7874 0.4064)
			(end 0.7874 -0.4064)
			(stroke
				(width 0.1524)
				(type default)
			)
			(layer "B.SilkS")
		)
		(fp_line
			(start -0.7874 -0.4064)
			(end -0.7874 0.4064)
			(stroke
				(width 0.1524)
				(type default)
			)
			(layer "B.SilkS")
		)
		(fp_line
			(start 0.7874 -0.4064)
			(end -0.7874 -0.4064)
			(stroke
				(width 0.1524)
				(type default)
			)
			(layer "B.SilkS")
		)
		(fp_line
			(start -0.67945 0.3048)
			(end -0.120396 0.3048)
			(stroke
				(width 0.1)
				(type default)
			)
			(layer "B.Fab")
		)
		(fp_line
			(start -0.120396 0.3048)
			(end -0.120396 0.2794)
			(stroke
				(width 0.1)
				(type default)
			)
			(layer "B.Fab")
		)
		(fp_line
			(start 0.12065 0.3048)
			(end 0.67945 0.3048)
			(stroke
				(width 0.1)
				(type default)
			)
			(layer "B.Fab")
		)
		(fp_line
			(start 0.67945 0.3048)
			(end 0.67945 -0.305054)
			(stroke
				(width 0.1)
				(type default)
			)
			(layer "B.Fab")
		)
		(fp_line
			(start -0.120396 0.2794)
			(end 0.12065 0.2794)
			(stroke
				(width 0.1)
				(type default)
			)
			(layer "B.Fab")
		)
		(fp_line
			(start 0.12065 0.2794)
			(end 0.12065 0.3048)
			(stroke
				(width 0.1)
				(type default)
			)
			(layer "B.Fab")
		)
		(fp_line
			(start -0.12065 -0.2794)
			(end -0.12065 -0.3048)
			(stroke
				(width 0.1)
				(type default)
			)
			(layer "B.Fab")
		)
		(fp_line
			(start 0.12065 -0.2794)
			(end -0.12065 -0.2794)
			(stroke
				(width 0.1)
				(type default)
			)
			(layer "B.Fab")
		)
		(fp_line
			(start -0.67945 -0.3048)
			(end -0.67945 0.3048)
			(stroke
				(width 0.1)
				(type default)
			)
			(layer "B.Fab")
		)
		(fp_line
			(start -0.12065 -0.3048)
			(end -0.67945 -0.3048)
			(stroke
				(width 0.1)
				(type default)
			)
			(layer "B.Fab")
		)
		(fp_line
			(start 0.12065 -0.305054)
			(end 0.12065 -0.2794)
			(stroke
				(width 0.1)
				(type default)
			)
			(layer "B.Fab")
		)
		(fp_line
			(start 0.67945 -0.305054)
			(end 0.12065 -0.305054)
			(stroke
				(width 0.1)
				(type default)
			)
			(layer "B.Fab")
		)
		(pad "1" smd circle
			(at 0.40005 0 90)
			(size 0 0)
			(layers "B.Cu" "B.Mask" "B.Paste")
			(net "PWRGD_DRAMPWRGD_CPU1_EF_LVC1_R2")
		)
		(pad "2" smd circle
			(at -0.40005 0 90)
			(size 0 0)
			(layers "B.Cu" "B.Mask" "B.Paste")
			(net "PWRGD_DRAMPWRGD_CPU1_EF_LVC1_R")
		)
	)
)
